(kicad_pcb
	(version 20260206)
	(generator "pcbnew")
	(generator_version "10.0")
	(general
		(thickness 1.6)
		(legacy_teardrops no)
	)
	(paper "A4")
	(title_block
		(title "v1-pdb — T6M_PDB_D_0927_0900.brd")
		(comment 1 "Open CloudServer (Microsoft) / footprints 188-197 of 321")
	)
	(layers
		(0 "F.Cu" signal "TOP")
		(4 "In1.Cu" signal "GND")
		(6 "In2.Cu" signal "IN1")
		(8 "In3.Cu" signal "VCC")
		(10 "In4.Cu" signal "VCC1")
		(12 "In5.Cu" signal "IN2")
		(14 "In6.Cu" signal "GND1")
		(2 "B.Cu" signal "BOTTOM")
		(9 "F.Adhes" user "F.Adhesive")
		(11 "B.Adhes" user "B.Adhesive")
		(13 "F.Paste" user "Package Geometry/Pastemask Top")
		(15 "B.Paste" user "Package Geometry/Pastemask Bottom")
		(5 "F.SilkS" user "Ref Des/Silkscreen Top")
		(7 "B.SilkS" user "Ref Des/Silkscreen Bottom")
		(1 "F.Mask" user "Board Geometry/Soldermask Top")
		(3 "B.Mask" user "Board Geometry/Soldermask Bottom")
		(17 "Dwgs.User" user "User.Drawings")
		(19 "Cmts.User" user "User.Comments")
		(21 "Eco1.User" user "User.Eco1")
		(23 "Eco2.User" user "User.Eco2")
		(25 "Edge.Cuts" user "Board Geometry/Outline")
		(27 "Margin" user)
		(31 "F.CrtYd" user "Package Geometry/Place Bound Top")
		(29 "B.CrtYd" user "Package Geometry/Place Bound Bottom")
		(35 "F.Fab" user "Ref Des/Assembly Top")
		(33 "B.Fab" user "Ref Des/Assembly Bottom")
	)
	(footprint ""
		(layer "F.Cu")
		(at 25.931622 -100.590096)
		(property "Reference" "R67"
			(at -4.080256 -0.075692 0)
			(unlocked yes)
			(layer "F.SilkS")
			(effects
				(font
					(size 0.7874 0.5842)
					(thickness 0.1524)
				)
				(justify left)
			)
		)
		(property "Value" ""
			(at 0 0 0)
			(layer "F.Fab")
			(effects
				(font
					(size 1.27 1.27)
				)
			)
		)
		(duplicate_pad_numbers_are_jumpers no)
		(fp_line
			(start -0.7874 -0.4064)
			(end 0.7874 -0.4064)
			(stroke
				(width 0.1524)
				(type default)
			)
			(layer "F.SilkS")
		)
		(fp_line
			(start -0.7874 0.4064)
			(end -0.7874 -0.4064)
			(stroke
				(width 0.1524)
				(type default)
			)
			(layer "F.SilkS")
		)
		(fp_line
			(start 0.7874 -0.4064)
			(end 0.7874 0.4064)
			(stroke
				(width 0.1524)
				(type default)
			)
			(layer "F.SilkS")
		)
		(fp_line
			(start 0.7874 0.4064)
			(end -0.7874 0.4064)
			(stroke
				(width 0.1524)
				(type default)
			)
			(layer "F.SilkS")
		)
		(fp_poly
			(pts
				(xy -0.508 0.2794) (xy -0.508 0.2286) (xy -0.635 0.2286) (xy -0.635 -0.254) (xy -0.5334 -0.254)
				(xy -0.5334 -0.2794) (xy 0.5334 -0.2794) (xy 0.5334 -0.254) (xy 0.635 -0.254) (xy 0.635 0.254) (xy 0.5334 0.254)
				(xy 0.5334 0.2794)
			)
			(stroke
				(width 0)
				(type default)
			)
			(fill no)
			(layer "F.CrtYd")
		)
		(pad "1" smd rect
			(at 0.40005 0)
			(size 0.4572 0.508)
			(layers "F.Cu" "F.Mask" "F.Paste")
			(net "PSU2_PS_KILL")
		)
		(pad "2" smd rect
			(at -0.40005 0)
			(size 0.4572 0.508)
			(layers "F.Cu" "F.Mask" "F.Paste")
			(net "GND")
		)
	)
	(footprint ""
		(layer "F.Cu")
		(at 73.687178 -263.260078 90)
		(property "Reference" "C47"
			(at -4.374134 0.10795 90)
			(unlocked yes)
			(layer "F.SilkS")
			(effects
				(font
					(size 0.7874 0.5842)
					(thickness 0.1524)
				)
				(justify left)
			)
		)
		(property "Value" ""
			(at 0 0 90)
			(layer "F.Fab")
			(effects
				(font
					(size 1.27 1.27)
				)
			)
		)
		(duplicate_pad_numbers_are_jumpers no)
		(fp_line
			(start 0.7874 -0.4064)
			(end 0.7874 0.4064)
			(stroke
				(width 0.1524)
				(type default)
			)
			(layer "F.SilkS")
		)
		(fp_line
			(start -0.7874 -0.4064)
			(end 0.7874 -0.4064)
			(stroke
				(width 0.1524)
				(type default)
			)
			(layer "F.SilkS")
		)
		(fp_line
			(start 0 0.381)
			(end 0 -0.381)
			(stroke
				(width 0.1524)
				(type default)
			)
			(layer "F.SilkS")
		)
		(fp_line
			(start 0.7874 0.4064)
			(end -0.7874 0.4064)
			(stroke
				(width 0.1524)
				(type default)
			)
			(layer "F.SilkS")
		)
		(fp_line
			(start -0.7874 0.4064)
			(end -0.7874 -0.4064)
			(stroke
				(width 0.1524)
				(type default)
			)
			(layer "F.SilkS")
		)
		(fp_poly
			(pts
				(xy -0.5334 0.254) (xy -0.635 0.254) (xy -0.635 0.2286) (xy -0.635 -0.254) (xy -0.5334 -0.254) (xy -0.5334 -0.2794)
				(xy 0.5334 -0.2794) (xy 0.5334 -0.254) (xy 0.635 -0.254) (xy 0.635 0.254) (xy 0.5334 0.254) (xy 0.5334 0.2794)
				(xy -0.508 0.2794) (xy -0.5334 0.2794)
			)
			(stroke
				(width 0)
				(type default)
			)
			(fill no)
			(layer "F.CrtYd")
		)
		(pad "1" smd rect
			(at 0.40005 0 90)
			(size 0.4572 0.508)
			(layers "F.Cu" "F.Mask" "F.Paste")
			(net "P12V")
		)
		(pad "2" smd rect
			(at -0.40005 0 90)
			(size 0.4572 0.508)
			(layers "F.Cu" "F.Mask" "F.Paste")
			(net "GND")
		)
	)
	(footprint ""
		(layer "F.Cu")
		(at 72.590152 -220.425772 90)
		(property "Reference" "C39"
			(at -3.945636 0.03175 90)
			(unlocked yes)
			(layer "F.SilkS")
			(effects
				(font
					(size 0.7874 0.5842)
					(thickness 0.1524)
				)
				(justify left)
			)
		)
		(property "Value" ""
			(at 0 0 90)
			(layer "F.Fab")
			(effects
				(font
					(size 1.27 1.27)
				)
			)
		)
		(duplicate_pad_numbers_are_jumpers no)
		(fp_line
			(start 0.7874 -0.4064)
			(end 0.7874 0.4064)
			(stroke
				(width 0.1524)
				(type default)
			)
			(layer "F.SilkS")
		)
		(fp_line
			(start -0.7874 -0.4064)
			(end 0.7874 -0.4064)
			(stroke
				(width 0.1524)
				(type default)
			)
			(layer "F.SilkS")
		)
		(fp_line
			(start 0 0.381)
			(end 0 -0.381)
			(stroke
				(width 0.1524)
				(type default)
			)
			(layer "F.SilkS")
		)
		(fp_line
			(start 0.7874 0.4064)
			(end -0.7874 0.4064)
			(stroke
				(width 0.1524)
				(type default)
			)
			(layer "F.SilkS")
		)
		(fp_line
			(start -0.7874 0.4064)
			(end -0.7874 -0.4064)
			(stroke
				(width 0.1524)
				(type default)
			)
			(layer "F.SilkS")
		)
		(fp_poly
			(pts
				(xy -0.5334 0.254) (xy -0.635 0.254) (xy -0.635 0.2286) (xy -0.635 -0.254) (xy -0.5334 -0.254) (xy -0.5334 -0.2794)
				(xy 0.5334 -0.2794) (xy 0.5334 -0.254) (xy 0.635 -0.254) (xy 0.635 0.254) (xy 0.5334 0.254) (xy 0.5334 0.2794)
				(xy -0.508 0.2794) (xy -0.5334 0.2794)
			)
			(stroke
				(width 0)
				(type default)
			)
			(fill no)
			(layer "F.CrtYd")
		)
		(pad "1" smd rect
			(at 0.40005 0 90)
			(size 0.4572 0.508)
			(layers "F.Cu" "F.Mask" "F.Paste")
			(net "P12V")
		)
		(pad "2" smd rect
			(at -0.40005 0 90)
			(size 0.4572 0.508)
			(layers "F.Cu" "F.Mask" "F.Paste")
			(net "GND")
		)
	)
	(footprint ""
		(layer "F.Cu")
		(at 79.898748 -504.572778 -90)
		(property "Reference" "C78"
			(at -3.551682 0.005842 90)
			(unlocked yes)
			(layer "F.SilkS")
			(effects
				(font
					(size 0.7874 0.5842)
					(thickness 0.1524)
				)
			)
		)
		(property "Value" ""
			(at 0 0 270)
			(layer "F.Fab")
			(effects
				(font
					(size 1.27 1.27)
				)
			)
		)
		(duplicate_pad_numbers_are_jumpers no)
		(fp_line
			(start -1.2954 0.5842)
			(end -1.2954 -0.5842)
			(stroke
				(width 0.1524)
				(type default)
			)
			(layer "F.SilkS")
		)
		(fp_line
			(start 1.2954 0.5842)
			(end -1.2954 0.5842)
			(stroke
				(width 0.1524)
				(type default)
			)
			(layer "F.SilkS")
		)
		(fp_line
			(start -1.2954 -0.5842)
			(end 1.2954 -0.5842)
			(stroke
				(width 0.1524)
				(type default)
			)
			(layer "F.SilkS")
		)
		(fp_line
			(start 0 -0.5842)
			(end 0 0.5842)
			(stroke
				(width 0.1524)
				(type default)
			)
			(layer "F.SilkS")
		)
		(fp_line
			(start 1.2954 -0.5842)
			(end 1.2954 0.5842)
			(stroke
				(width 0.1524)
				(type default)
			)
			(layer "F.SilkS")
		)
		(fp_poly
			(pts
				(xy 0.8636 -0.4572) (xy 0.8636 -0.3556) (xy 1.143 -0.3556) (xy 1.143 0.3556) (xy 0.8636 0.3556)
				(xy 0.8636 0.4572) (xy -0.8636 0.4572) (xy -0.8636 0.3556) (xy -1.143 0.3556) (xy -1.143 -0.3556)
				(xy -0.8636 -0.3556) (xy -0.8636 -0.4572)
			)
			(stroke
				(width 0)
				(type default)
			)
			(fill no)
			(layer "F.CrtYd")
		)
		(fp_line
			(start -0.884936 0.504952)
			(end -0.884936 -0.504952)
			(stroke
				(width 0.1)
				(type default)
			)
			(layer "F.Fab")
		)
		(fp_line
			(start 0.884936 0.504952)
			(end -0.884936 0.504952)
			(stroke
				(width 0.1)
				(type default)
			)
			(layer "F.Fab")
		)
		(fp_line
			(start -0.884936 -0.504952)
			(end 0.884936 -0.504952)
			(stroke
				(width 0.1)
				(type default)
			)
			(layer "F.Fab")
		)
		(fp_line
			(start 0.884936 -0.504952)
			(end 0.884936 0.504952)
			(stroke
				(width 0.1)
				(type default)
			)
			(layer "F.Fab")
		)
		(pad "1" smd rect
			(at 0.7366 0)
			(size 0.7112 0.8128)
			(layers "F.Cu" "F.Mask" "F.Paste")
			(net "P12V")
		)
		(pad "2" smd rect
			(at -0.7366 0)
			(size 0.7112 0.8128)
			(layers "F.Cu" "F.Mask" "F.Paste")
			(net "GND")
		)
	)
	(footprint ""
		(layer "F.Cu")
		(at 70.85457 -175.945546 90)
		(property "Reference" "C33"
			(at -4.154424 0.196088 90)
			(unlocked yes)
			(layer "F.SilkS")
			(effects
				(font
					(size 0.7874 0.5842)
					(thickness 0.1524)
				)
				(justify left)
			)
		)
		(property "Value" ""
			(at 0 0 90)
			(layer "F.Fab")
			(effects
				(font
					(size 1.27 1.27)
				)
			)
		)
		(duplicate_pad_numbers_are_jumpers no)
		(fp_line
			(start 0.7874 -0.4064)
			(end 0.7874 0.4064)
			(stroke
				(width 0.1524)
				(type default)
			)
			(layer "F.SilkS")
		)
		(fp_line
			(start -0.7874 -0.4064)
			(end 0.7874 -0.4064)
			(stroke
				(width 0.1524)
				(type default)
			)
			(layer "F.SilkS")
		)
		(fp_line
			(start 0 0.381)
			(end 0 -0.381)
			(stroke
				(width 0.1524)
				(type default)
			)
			(layer "F.SilkS")
		)
		(fp_line
			(start 0.7874 0.4064)
			(end -0.7874 0.4064)
			(stroke
				(width 0.1524)
				(type default)
			)
			(layer "F.SilkS")
		)
		(fp_line
			(start -0.7874 0.4064)
			(end -0.7874 -0.4064)
			(stroke
				(width 0.1524)
				(type default)
			)
			(layer "F.SilkS")
		)
		(fp_poly
			(pts
				(xy -0.5334 0.254) (xy -0.635 0.254) (xy -0.635 0.2286) (xy -0.635 -0.254) (xy -0.5334 -0.254) (xy -0.5334 -0.2794)
				(xy 0.5334 -0.2794) (xy 0.5334 -0.254) (xy 0.635 -0.254) (xy 0.635 0.254) (xy 0.5334 0.254) (xy 0.5334 0.2794)
				(xy -0.508 0.2794) (xy -0.5334 0.2794)
			)
			(stroke
				(width 0)
				(type default)
			)
			(fill no)
			(layer "F.CrtYd")
		)
		(pad "1" smd rect
			(at 0.40005 0 90)
			(size 0.4572 0.508)
			(layers "F.Cu" "F.Mask" "F.Paste")
			(net "P12V")
		)
		(pad "2" smd rect
			(at -0.40005 0 90)
			(size 0.4572 0.508)
			(layers "F.Cu" "F.Mask" "F.Paste")
			(net "GND")
		)
	)
	(footprint ""
		(layer "F.Cu")
		(at 25.997662 -9.509252)
		(property "Reference" "R63"
			(at -3.764788 0.113792 0)
			(unlocked yes)
			(layer "F.SilkS")
			(effects
				(font
					(size 0.7874 0.5842)
					(thickness 0.1524)
				)
				(justify left)
			)
		)
		(property "Value" ""
			(at 0 0 0)
			(layer "F.Fab")
			(effects
				(font
					(size 1.27 1.27)
				)
			)
		)
		(duplicate_pad_numbers_are_jumpers no)
		(fp_line
			(start -0.7874 -0.4064)
			(end 0.7874 -0.4064)
			(stroke
				(width 0.1524)
				(type default)
			)
			(layer "F.SilkS")
		)
		(fp_line
			(start -0.7874 0.4064)
			(end -0.7874 -0.4064)
			(stroke
				(width 0.1524)
				(type default)
			)
			(layer "F.SilkS")
		)
		(fp_line
			(start 0.7874 -0.4064)
			(end 0.7874 0.4064)
			(stroke
				(width 0.1524)
				(type default)
			)
			(layer "F.SilkS")
		)
		(fp_line
			(start 0.7874 0.4064)
			(end -0.7874 0.4064)
			(stroke
				(width 0.1524)
				(type default)
			)
			(layer "F.SilkS")
		)
		(fp_poly
			(pts
				(xy -0.508 0.2794) (xy -0.508 0.2286) (xy -0.635 0.2286) (xy -0.635 -0.254) (xy -0.5334 -0.254)
				(xy -0.5334 -0.2794) (xy 0.5334 -0.2794) (xy 0.5334 -0.254) (xy 0.635 -0.254) (xy 0.635 0.254) (xy 0.5334 0.254)
				(xy 0.5334 0.2794)
			)
			(stroke
				(width 0)
				(type default)
			)
			(fill no)
			(layer "F.CrtYd")
		)
		(pad "1" smd rect
			(at 0.40005 0)
			(size 0.4572 0.508)
			(layers "F.Cu" "F.Mask" "F.Paste")
			(net "PSU1_PS_KILL")
		)
		(pad "2" smd rect
			(at -0.40005 0)
			(size 0.4572 0.508)
			(layers "F.Cu" "F.Mask" "F.Paste")
			(net "GND")
		)
	)
	(footprint ""
		(layer "F.Cu")
		(at 74.626978 -307.819806 90)
		(property "Reference" "C53"
			(at -1.302004 5.422138 90)
			(unlocked yes)
			(layer "F.SilkS")
			(effects
				(font
					(size 0.7874 0.5842)
					(thickness 0.1524)
				)
				(justify left)
			)
		)
		(property "Value" ""
			(at 0 0 90)
			(layer "F.Fab")
			(effects
				(font
					(size 1.27 1.27)
				)
			)
		)
		(duplicate_pad_numbers_are_jumpers no)
		(fp_line
			(start 0.7874 -0.4064)
			(end 0.7874 0.4064)
			(stroke
				(width 0.1524)
				(type default)
			)
			(layer "F.SilkS")
		)
		(fp_line
			(start -0.7874 -0.4064)
			(end 0.7874 -0.4064)
			(stroke
				(width 0.1524)
				(type default)
			)
			(layer "F.SilkS")
		)
		(fp_line
			(start 0 0.381)
			(end 0 -0.381)
			(stroke
				(width 0.1524)
				(type default)
			)
			(layer "F.SilkS")
		)
		(fp_line
			(start 0.7874 0.4064)
			(end -0.7874 0.4064)
			(stroke
				(width 0.1524)
				(type default)
			)
			(layer "F.SilkS")
		)
		(fp_line
			(start -0.7874 0.4064)
			(end -0.7874 -0.4064)
			(stroke
				(width 0.1524)
				(type default)
			)
			(layer "F.SilkS")
		)
		(fp_poly
			(pts
				(xy -0.5334 0.254) (xy -0.635 0.254) (xy -0.635 0.2286) (xy -0.635 -0.254) (xy -0.5334 -0.254) (xy -0.5334 -0.2794)
				(xy 0.5334 -0.2794) (xy 0.5334 -0.254) (xy 0.635 -0.254) (xy 0.635 0.254) (xy 0.5334 0.254) (xy 0.5334 0.2794)
				(xy -0.508 0.2794) (xy -0.5334 0.2794)
			)
			(stroke
				(width 0)
				(type default)
			)
			(fill no)
			(layer "F.CrtYd")
		)
		(pad "1" smd rect
			(at 0.40005 0 90)
			(size 0.4572 0.508)
			(layers "F.Cu" "F.Mask" "F.Paste")
			(net "P12V")
		)
		(pad "2" smd rect
			(at -0.40005 0 90)
			(size 0.4572 0.508)
			(layers "F.Cu" "F.Mask" "F.Paste")
			(net "GND")
		)
	)
	(footprint ""
		(layer "F.Cu")
		(at 27.29357 -280.04389)
		(property "Reference" "R137"
			(at -3.851402 0.175768 0)
			(unlocked yes)
			(layer "F.SilkS")
			(effects
				(font
					(size 0.7874 0.5842)
					(thickness 0.1524)
				)
				(justify left)
			)
		)
		(property "Value" ""
			(at 0 0 0)
			(layer "F.Fab")
			(effects
				(font
					(size 1.27 1.27)
				)
			)
		)
		(duplicate_pad_numbers_are_jumpers no)
		(fp_line
			(start -0.7874 -0.4064)
			(end 0.7874 -0.4064)
			(stroke
				(width 0.1524)
				(type default)
			)
			(layer "F.SilkS")
		)
		(fp_line
			(start -0.7874 0.4064)
			(end -0.7874 -0.4064)
			(stroke
				(width 0.1524)
				(type default)
			)
			(layer "F.SilkS")
		)
		(fp_line
			(start 0.7874 -0.4064)
			(end 0.7874 0.4064)
			(stroke
				(width 0.1524)
				(type default)
			)
			(layer "F.SilkS")
		)
		(fp_line
			(start 0.7874 0.4064)
			(end -0.7874 0.4064)
			(stroke
				(width 0.1524)
				(type default)
			)
			(layer "F.SilkS")
		)
		(fp_poly
			(pts
				(xy -0.508 0.2794) (xy -0.508 0.2286) (xy -0.635 0.2286) (xy -0.635 -0.254) (xy -0.5334 -0.254)
				(xy -0.5334 -0.2794) (xy 0.5334 -0.2794) (xy 0.5334 -0.254) (xy 0.635 -0.254) (xy 0.635 0.254) (xy 0.5334 0.254)
				(xy 0.5334 0.2794)
			)
			(stroke
				(width 0)
				(type default)
			)
			(fill no)
			(layer "F.CrtYd")
		)
		(pad "1" smd rect
			(at 0.40005 0)
			(size 0.4572 0.508)
			(layers "F.Cu" "F.Mask" "F.Paste")
			(net "PSU4_CSAHRE")
		)
		(pad "2" smd rect
			(at -0.40005 0)
			(size 0.4572 0.508)
			(layers "F.Cu" "F.Mask" "F.Paste")
			(net "PSU_CSAHRE")
		)
	)
	(footprint ""
		(layer "F.Cu")
		(at 26.226008 -448.493388)
		(property "Reference" "R85"
			(at -3.597402 -0.121666 0)
			(unlocked yes)
			(layer "F.SilkS")
			(effects
				(font
					(size 0.7874 0.5842)
					(thickness 0.1524)
				)
				(justify left)
			)
		)
		(property "Value" ""
			(at 0 0 0)
			(layer "F.Fab")
			(effects
				(font
					(size 1.27 1.27)
				)
			)
		)
		(duplicate_pad_numbers_are_jumpers no)
		(fp_line
			(start -0.7874 -0.4064)
			(end 0.7874 -0.4064)
			(stroke
				(width 0.1524)
				(type default)
			)
			(layer "F.SilkS")
		)
		(fp_line
			(start -0.7874 0.4064)
			(end -0.7874 -0.4064)
			(stroke
				(width 0.1524)
				(type default)
			)
			(layer "F.SilkS")
		)
		(fp_line
			(start 0.7874 -0.4064)
			(end 0.7874 0.4064)
			(stroke
				(width 0.1524)
				(type default)
			)
			(layer "F.SilkS")
		)
		(fp_line
			(start 0.7874 0.4064)
			(end -0.7874 0.4064)
			(stroke
				(width 0.1524)
				(type default)
			)
			(layer "F.SilkS")
		)
		(fp_poly
			(pts
				(xy -0.508 0.2794) (xy -0.508 0.2286) (xy -0.635 0.2286) (xy -0.635 -0.254) (xy -0.5334 -0.254)
				(xy -0.5334 -0.2794) (xy 0.5334 -0.2794) (xy 0.5334 -0.254) (xy 0.635 -0.254) (xy 0.635 0.254) (xy 0.5334 0.254)
				(xy 0.5334 0.2794)
			)
			(stroke
				(width 0)
				(type default)
			)
			(fill no)
			(layer "F.CrtYd")
		)
		(pad "1" smd rect
			(at 0.40005 0)
			(size 0.4572 0.508)
			(layers "F.Cu" "F.Mask" "F.Paste")
			(net "PSU6_RESET")
		)
		(pad "2" smd rect
			(at -0.40005 0)
			(size 0.4572 0.508)
			(layers "F.Cu" "F.Mask" "F.Paste")
			(net "GND")
		)
	)
	(footprint ""
		(layer "F.Cu")
		(at 50.284126 -395.548358 180)
		(property "Reference" "CE18"
			(at -3.83413 -2.721864 0)
			(unlocked yes)
			(layer "F.SilkS")
			(effects
				(font
					(size 0.7874 0.5842)
					(thickness 0.1524)
				)
				(justify left)
			)
		)
		(property "Value" ""
			(at 0 0 180)
			(layer "F.Fab")
			(effects
				(font
					(size 1.27 1.27)
				)
			)
		)
		(duplicate_pad_numbers_are_jumpers no)
		(fp_line
			(start 0 -4.2672)
			(end 0 4.2672)
			(stroke
				(width 0.1524)
				(type default)
			)
			(layer "F.SilkS")
		)
		(fp_circle
			(center 0 0)
			(end -4.2672 0)
			(stroke
				(width 0.1524)
				(type default)
			)
			(fill no)
			(layer "F.SilkS")
		)
		(fp_poly
			(pts
				(arc
					(start 0 -4.2672)
					(mid 4.2672 0)
					(end 0 4.2672)
				)
			)
			(stroke
				(width 0)
				(type default)
			)
			(fill yes)
			(layer "F.SilkS")
		)
		(fp_poly
			(pts
				(xy -2.5146 -0.762) (xy -0.9906 -0.762) (xy -0.9906 0.762) (xy -2.5146 0.762)
			)
			(stroke
				(width 0)
				(type default)
			)
			(fill no)
			(layer "B.CrtYd")
		)
		(fp_poly
			(pts
				(arc
					(start 1.7526 0.762)
					(mid 2.291415 -0.538815)
					(end 0.9906 0)
				)
				(arc
					(start 0.9906 0.0254)
					(mid 1.206345 0.546255)
					(end 1.7272 0.762)
				)
			)
			(stroke
				(width 0)
				(type default)
			)
			(fill no)
			(layer "B.CrtYd")
		)
		(fp_poly
			(pts
				(arc
					(start -4.2672 0)
					(mid 4.2672 0)
					(end -4.2672 0)
				)
			)
			(stroke
				(width 0)
				(type default)
			)
			(fill no)
			(layer "F.CrtYd")
		)
		(fp_circle
			(center 0 0)
			(end -4.2672 0)
			(stroke
				(width 0.1)
				(type default)
			)
			(fill no)
			(layer "F.Fab")
		)
		(fp_text user "+"
			(at -4.934204 -1.625854 180)
			(unlocked yes)
			(layer "F.SilkS")
			(effects
				(font
					(size 0.7874 0.5842)
					(thickness 0.1524)
				)
				(justify left)
			)
		)
		(fp_text user "+"
			(at -5.6642 -0.34925 180)
			(unlocked yes)
			(layer "F.Fab")
			(effects
				(font
					(size 1.905 1.4224)
					(thickness 0.000001)
				)
				(justify left)
			)
		)
		(pad "1" thru_hole rect
			(at -1.75006 0 180)
			(size 1.397 1.397)
			(drill 0.9144)
			(layers "*.Cu" "*.Mask")
			(remove_unused_layers no)
			(net "P12V")
			(clearance 0.0127)
			(thermal_gap 0.0127)
			(padstack
				(mode front_inner_back)
				(layer "Inner"
					(shape circle)
					(size 1.397 1.397)
					(clearance 0.0127)
				)
				(layer "B.Cu"
					(shape rect)
					(size 1.397 1.397)
					(clearance 0.0127)
				)
			)
		)
		(pad "2" thru_hole circle
			(at 1.75006 0 180)
			(size 1.397 1.397)
			(drill 0.9144)
			(layers "*.Cu" "*.Mask")
			(remove_unused_layers no)
			(net "GND")
			(clearance 0.0127)
			(thermal_gap 0.0127)
		)
	)
)
